G04 ================== begin FILE IDENTIFICATION RECORD ==================*
G04 Layout Name:  16368-sb.brd*
G04 Film Name:    BMASK*
G04 File Format:  Gerber RS274X*
G04 File Origin:  Cadence Allegro 16.5-S056*
G04 Origin Date:  Tue Feb 07 09:07:39 2017*
G04 *
G04 Layer:  VIA CLASS/SOLDERMASK_BOTTOM*
G04 Layer:  PIN/SOLDERMASK_BOTTOM*
G04 Layer:  PACKAGE GEOMETRY/SOLDERMASK_BOTTOM*
G04 Layer:  DRAWING FORMAT/LAYER_PCB_STORY*
G04 Layer:  DRAWING FORMAT/LAYER_SOLDER_B*
G04 Layer:  BOARD GEOMETRY/SOLDERMASK_BOTTOM*
G04 *
G04 Offset:    (0.00 0.00)*
G04 Mirror:    No*
G04 Mode:      Positive*
G04 Rotation:  0*
G04 FullContactRelief:  No*
G04 UndefLineWidth:     6.00*
G04 ================== end FILE IDENTIFICATION RECORD ====================*
%FSLAX35Y35*MOIN*%
%IR0*IPPOS*OFA0.00000B0.00000*MIA0B0*SFA1.00000B1.00000*%
%AMMACRO20*
4,1,40,.011,.007,
.011,-.007,
.010939,-.007695,
.010759,-.008368,
.010464,-.009,
.010064,-.009571,
.009571,-.010064,
.009,-.010464,
.008368,-.010759,
.007695,-.010939,
.007,-.011,
-.007,-.011,
-.007695,-.010939,
-.008368,-.010759,
-.009,-.010464,
-.009571,-.010064,
-.010064,-.009571,
-.010464,-.009,
-.010759,-.008368,
-.010939,-.007695,
-.011,-.007,
-.011,.007,
-.010939,.007695,
-.010759,.008368,
-.010464,.009,
-.010064,.009571,
-.009571,.010064,
-.009,.010464,
-.008368,.010759,
-.007695,.010939,
-.007,.011,
.007,.011,
.007695,.010939,
.008368,.010759,
.009,.010464,
.009571,.010064,
.010064,.009571,
.010464,.009,
.010759,.008368,
.010939,.007695,
.011,.007,
0.0*
%
%ADD20MACRO20*%
%ADD29C,.04*%
%ADD27C,.014*%
%ADD28C,.024*%
%ADD15C,.042*%
%ADD12C,.034*%
%ADD16R,.039X.108*%
%ADD14C,.026*%
%ADD10C,.08*%
%ADD13C,.086*%
%AMMACRO31*
4,1,40,-.011,-.007,
-.011,.007,
-.010939,.007695,
-.010759,.008368,
-.010464,.009,
-.010064,.009571,
-.009571,.010064,
-.009,.010464,
-.008368,.010759,
-.007695,.010939,
-.007,.011,
.007,.011,
.007695,.010939,
.008368,.010759,
.009,.010464,
.009571,.010064,
.010064,.009571,
.010464,.009,
.010759,.008368,
.010939,.007695,
.011,.007,
.011,-.007,
.010939,-.007695,
.010759,-.008368,
.010464,-.009,
.010064,-.009571,
.009571,-.010064,
.009,-.010464,
.008368,-.010759,
.007695,-.010939,
.007,-.011,
-.007,-.011,
-.007695,-.010939,
-.008368,-.010759,
-.009,-.010464,
-.009571,-.010064,
-.010064,-.009571,
-.010464,-.009,
-.010759,-.008368,
-.010939,-.007695,
-.011,-.007,
0.0*
%
%ADD31MACRO31*%
%AMMACRO17*
4,1,40,.007,-.011,
-.007,-.011,
-.007695,-.010939,
-.008368,-.010759,
-.009,-.010464,
-.009571,-.010064,
-.010064,-.009571,
-.010464,-.009,
-.010759,-.008368,
-.010939,-.007695,
-.011,-.007,
-.011,.007,
-.010939,.007695,
-.010759,.008368,
-.010464,.009,
-.010064,.009571,
-.009571,.010064,
-.009,.010464,
-.008368,.010759,
-.007695,.010939,
-.007,.011,
.007,.011,
.007695,.010939,
.008368,.010759,
.009,.010464,
.009571,.010064,
.010064,.009571,
.010464,.009,
.010759,.008368,
.010939,.007695,
.011,.007,
.011,-.007,
.010939,-.007695,
.010759,-.008368,
.010464,-.009,
.010064,-.009571,
.009571,-.010064,
.009,-.010464,
.008368,-.010759,
.007695,-.010939,
.007,-.011,
0.0*
%
%ADD17MACRO17*%
%AMMACRO24*
4,1,44,.023,.00387,
.022901,.005261,
.022562,.006614,
.021993,.007887,
.021211,.009042,
.020241,.010044,
.019112,.010863,
.017857,.011472,
.016516,.011855,
.015129,.011999,
.015,.012,
-.015,.012,
-.016389,.011878,
-.017737,.011517,
-.019001,.010928,
-.020143,.010128,
-.021129,.009142,
-.021929,.007999,
-.022519,.006735,
-.022879,.005388,
-.023001,.003999,
-.023,.00387,
-.023,-.00387,
-.022901,-.005261,
-.022562,-.006614,
-.021993,-.007887,
-.021211,-.009042,
-.020241,-.010044,
-.019112,-.010863,
-.017857,-.011472,
-.016516,-.011855,
-.015129,-.011999,
-.015,-.012,
.015,-.012,
.016389,-.011878,
.017737,-.011517,
.019001,-.010928,
.020143,-.010128,
.021129,-.009142,
.021929,-.007999,
.022519,-.006735,
.022879,-.005388,
.023001,-.003999,
.023,-.00387,
.023,.00387,
0.0*
%
%ADD24MACRO24*%
%AMMACRO25*
4,1,40,-.013,.017,
.013,.017,
.013695,.016939,
.014368,.016759,
.015,.016464,
.015571,.016064,
.016064,.015571,
.016464,.015,
.016759,.014368,
.016939,.013695,
.017,.013,
.017,-.013,
.016939,-.013695,
.016759,-.014368,
.016464,-.015,
.016064,-.015571,
.015571,-.016064,
.015,-.016464,
.014368,-.016759,
.013695,-.016939,
.013,-.017,
-.013,-.017,
-.013695,-.016939,
-.014368,-.016759,
-.015,-.016464,
-.015571,-.016064,
-.016064,-.015571,
-.016464,-.015,
-.016759,-.014368,
-.016939,-.013695,
-.017,-.013,
-.017,.013,
-.016939,.013695,
-.016759,.014368,
-.016464,.015,
-.016064,.015571,
-.015571,.016064,
-.015,.016464,
-.014368,.016759,
-.013695,.016939,
-.013,.017,
0.0*
%
%ADD25MACRO25*%
%AMMACRO32*
4,1,40,-.011,-.007,
-.011,.007,
-.010939,.007695,
-.010759,.008368,
-.010464,.009,
-.010064,.009571,
-.009571,.010064,
-.009,.010464,
-.008368,.010759,
-.007695,.010939,
-.007,.011,
.007,.011,
.007695,.010939,
.008368,.010759,
.009,.010464,
.009571,.010064,
.010064,.009571,
.010464,.009,
.010759,.008368,
.010939,.007695,
.011,.007,
.011,-.007,
.010939,-.007695,
.010759,-.008368,
.010464,-.009,
.010064,-.009571,
.009571,-.010064,
.009,-.010464,
.008368,-.010759,
.007695,-.010939,
.007,-.011,
-.007,-.011,
-.007695,-.010939,
-.008368,-.010759,
-.009,-.010464,
-.009571,-.010064,
-.010064,-.009571,
-.010464,-.009,
-.010759,-.008368,
-.010939,-.007695,
-.011,-.007,
0.0*
%
%ADD32MACRO32*%
%AMMACRO18*
4,1,40,.007,-.011,
-.007,-.011,
-.007695,-.010939,
-.008368,-.010759,
-.009,-.010464,
-.009571,-.010064,
-.010064,-.009571,
-.010464,-.009,
-.010759,-.008368,
-.010939,-.007695,
-.011,-.007,
-.011,.007,
-.010939,.007695,
-.010759,.008368,
-.010464,.009,
-.010064,.009571,
-.009571,.010064,
-.009,.010464,
-.008368,.010759,
-.007695,.010939,
-.007,.011,
.007,.011,
.007695,.010939,
.008368,.010759,
.009,.010464,
.009571,.010064,
.010064,.009571,
.010464,.009,
.010759,.008368,
.010939,.007695,
.011,.007,
.011,-.007,
.010939,-.007695,
.010759,-.008368,
.010464,-.009,
.010064,-.009571,
.009571,-.010064,
.009,-.010464,
.008368,-.010759,
.007695,-.010939,
.007,-.011,
0.0*
%
%ADD18MACRO18*%
%AMMACRO26*
4,1,40,-.013,.017,
.013,.017,
.013695,.016939,
.014368,.016759,
.015,.016464,
.015571,.016064,
.016064,.015571,
.016464,.015,
.016759,.014368,
.016939,.013695,
.017,.013,
.017,-.013,
.016939,-.013695,
.016759,-.014368,
.016464,-.015,
.016064,-.015571,
.015571,-.016064,
.015,-.016464,
.014368,-.016759,
.013695,-.016939,
.013,-.017,
-.013,-.017,
-.013695,-.016939,
-.014368,-.016759,
-.015,-.016464,
-.015571,-.016064,
-.016064,-.015571,
-.016464,-.015,
-.016759,-.014368,
-.016939,-.013695,
-.017,-.013,
-.017,.013,
-.016939,.013695,
-.016759,.014368,
-.016464,.015,
-.016064,.015571,
-.015571,.016064,
-.015,.016464,
-.014368,.016759,
-.013695,.016939,
-.013,.017,
0.0*
%
%ADD26MACRO26*%
%ADD30O,.04X.023*%
%ADD35R,.04X.022*%
%ADD21R,.032X.071*%
%ADD22R,.024X.063*%
%ADD23R,.016X.048*%
%ADD11C,.165*%
%AMMACRO34*
4,1,40,.008,-.012,
-.008,-.012,
-.008695,-.011939,
-.009368,-.011759,
-.01,-.011464,
-.010571,-.011064,
-.011064,-.010571,
-.011464,-.01,
-.011759,-.009368,
-.011939,-.008695,
-.012,-.008,
-.012,.008,
-.011939,.008695,
-.011759,.009368,
-.011464,.01,
-.011064,.010571,
-.010571,.011064,
-.01,.011464,
-.009368,.011759,
-.008695,.011939,
-.008,.012,
.008,.012,
.008695,.011939,
.009368,.011759,
.01,.011464,
.010571,.011064,
.011064,.010571,
.011464,.01,
.011759,.009368,
.011939,.008695,
.012,.008,
.012,-.008,
.011939,-.008695,
.011759,-.009368,
.011464,-.01,
.011064,-.010571,
.010571,-.011064,
.01,-.011464,
.009368,-.011759,
.008695,-.011939,
.008,-.012,
0.0*
%
%ADD34MACRO34*%
%AMMACRO19*
4,1,40,.011,.007,
.011,-.007,
.010939,-.007695,
.010759,-.008368,
.010464,-.009,
.010064,-.009571,
.009571,-.010064,
.009,-.010464,
.008368,-.010759,
.007695,-.010939,
.007,-.011,
-.007,-.011,
-.007695,-.010939,
-.008368,-.010759,
-.009,-.010464,
-.009571,-.010064,
-.010064,-.009571,
-.010464,-.009,
-.010759,-.008368,
-.010939,-.007695,
-.011,-.007,
-.011,.007,
-.010939,.007695,
-.010759,.008368,
-.010464,.009,
-.010064,.009571,
-.009571,.010064,
-.009,.010464,
-.008368,.010759,
-.007695,.010939,
-.007,.011,
.007,.011,
.007695,.010939,
.008368,.010759,
.009,.010464,
.009571,.010064,
.010064,.009571,
.010464,.009,
.010759,.008368,
.010939,.007695,
.011,.007,
0.0*
%
%ADD19MACRO19*%
%AMMACRO33*
4,1,40,.008,-.012,
-.008,-.012,
-.008695,-.011939,
-.009368,-.011759,
-.01,-.011464,
-.010571,-.011064,
-.011064,-.010571,
-.011464,-.01,
-.011759,-.009368,
-.011939,-.008695,
-.012,-.008,
-.012,.008,
-.011939,.008695,
-.011759,.009368,
-.011464,.01,
-.011064,.010571,
-.010571,.011064,
-.01,.011464,
-.009368,.011759,
-.008695,.011939,
-.008,.012,
.008,.012,
.008695,.011939,
.009368,.011759,
.01,.011464,
.010571,.011064,
.011064,.010571,
.011464,.01,
.011759,.009368,
.011939,.008695,
.012,.008,
.012,-.008,
.011939,-.008695,
.011759,-.009368,
.011464,-.01,
.011064,-.010571,
.010571,-.011064,
.01,-.011464,
.009368,-.011759,
.008695,-.011939,
.008,-.012,
0.0*
%
%ADD33MACRO33*%
%ADD36C,.02*%
%ADD37C,.006*%
G75*
%LPD*%
G75*
G36*
G01X21502Y10591D02*
G03X23769Y5144I1134J-2723D01*
G03X32258Y13633I-6052J14541D01*
G03X26811Y15900I-2724J1133D01*
G02X21502Y10591I-9094J3785D01*
G37*
G36*
G01X13932D02*
G02X11665Y5144I-1134J-2723D01*
G02X3176Y13633I6052J14541D01*
G02X8623Y15900I2724J1133D01*
G03X13932Y10591I9094J3785D01*
G37*
G36*
G01Y28779D02*
G03X11665Y34226I-1134J2723D01*
G03X3176Y25737I6052J-14541D01*
G03X8623Y23470I2724J-1133D01*
G02X13932Y28779I9094J-3785D01*
G37*
G36*
G01X21502D02*
G02X23769Y34226I1134J2723D01*
G02X32258Y25737I-6052J-14541D01*
G02X26811Y23470I-2724J-1133D01*
G03X21502Y28779I-9094J-3785D01*
G37*
G36*
G01X163234Y10591D02*
G03X165501Y5144I1134J-2723D01*
G03X173990Y13633I-6052J14541D01*
G03X168543Y15900I-2724J1133D01*
G02X163234Y10591I-9094J3785D01*
G37*
G36*
G01X155664D02*
G02X153397Y5144I-1134J-2723D01*
G02X144908Y13633I6052J14541D01*
G02X150355Y15900I2724J1133D01*
G03X155664Y10591I9094J3785D01*
G37*
G36*
G01Y28779D02*
G03X153397Y34226I-1134J2723D01*
G03X144908Y25737I6052J-14541D01*
G03X150355Y23470I2724J-1133D01*
G02X155664Y28779I9094J-3785D01*
G37*
G36*
G01X163234D02*
G02X165501Y34226I1134J2723D01*
G02X173990Y25737I-6052J-14541D01*
G02X168543Y23470I-2724J-1133D01*
G03X163234Y28779I-9094J-3785D01*
G37*
G54D10*
X25827Y-9492D03*
X148500Y47500D03*
X519227Y-9492D03*
G54D11*
X17717Y19685D03*
X159449D03*
G54D20*
X74500Y31200D03*
X70000Y51700D03*
G54D21*
X40158Y16142D03*
X105512D03*
G54D30*
X56418Y46949D03*
G54D12*
X28802Y13285D03*
X24117Y8600D03*
X11317D03*
X6632Y13285D03*
Y26085D03*
X11317Y30770D03*
X24117D03*
X28802Y26085D03*
X170534Y13285D03*
X165849Y8600D03*
X153049D03*
X148364Y13285D03*
Y26085D03*
X153049Y30770D03*
X165849D03*
X170534Y26085D03*
G54D22*
X45276Y6103D03*
X49213D03*
X53150D03*
X57087D03*
X61024D03*
X64961D03*
X68898D03*
X72835D03*
X76772D03*
X80709D03*
X84646D03*
X88583D03*
X92520D03*
X96457D03*
X100394D03*
G54D31*
X74000Y51700D03*
G54D13*
X9000Y48000D03*
X164500Y48500D03*
G54D23*
X85060Y31250D03*
X82500D03*
X79940D03*
Y53250D03*
X82500D03*
X85060D03*
Y46750D03*
X79940D03*
Y37750D03*
X85060D03*
G54D32*
X74000Y48300D03*
G54D14*
X26890Y46949D03*
G54D33*
X127500Y9200D03*
X131000D03*
G54D24*
X113950Y11000D03*
X121050Y13560D03*
Y8440D03*
G54D15*
X32205Y38484D03*
Y55414D03*
X51103Y38484D03*
Y55414D03*
G54D34*
X127500Y12800D03*
X131000D03*
G54D25*
X115800Y24100D03*
G54D16*
X115453Y35532D03*
X107579D03*
X99705D03*
X115453Y52264D03*
X107579D03*
X99705D03*
X123327Y35532D03*
X131201D03*
X123327Y52264D03*
X131201D03*
G54D35*
X132000Y21000D03*
X123000D03*
G54D26*
X110200Y24100D03*
G54D17*
X66900Y27500D03*
G54D36*
G01X-149983Y-76117D02*
Y-156117D01*
G01D02*
X864117D01*
G01X-153983Y-60117D02*
G02I-12000J0D01*
G01X-159133D02*
G02I-6850J0D01*
G01X-165983Y-76117D02*
Y-44117D01*
G01X-149983Y-60117D02*
X-181983D01*
G01X-149983Y-76117D02*
X864117D01*
G01X-149983Y-111617D02*
X864117D01*
G01X76617Y-76117D02*
Y-156117D01*
G01X214117Y-76117D02*
Y-156117D01*
G01X329117Y-76117D02*
Y-156117D01*
G01X496617Y-76117D02*
Y-156117D01*
G01X666617Y-76117D02*
Y-156117D01*
G01X864117Y-76117D02*
Y-156117D01*
G01X892117Y-60117D02*
G02I-12000J0D01*
G01X886967D02*
G02I-6850J0D01*
G01X880117Y-76117D02*
Y-44117D01*
G01X896117Y-60117D02*
X864117D01*
G54D18*
X70300Y27500D03*
G54D27*
X46000Y25600D03*
X111800Y52264D03*
X96000Y55600D03*
X111700Y39600D03*
X127500Y52264D03*
Y37000D03*
G54D37*
G01X-137600Y-128617D02*
Y-146117D01*
X-128866D01*
G01X-113987Y-136784D02*
X-113113Y-135909D01*
X-112458Y-134451D01*
X-112021Y-132408D01*
X-112458Y-130659D01*
X-113331Y-129492D01*
X-114860Y-128617D01*
X-120755D01*
Y-146117D01*
X-113550D01*
X-112021Y-144951D01*
X-111148Y-143200D01*
X-110711Y-141159D01*
X-111148Y-139117D01*
X-112458Y-137367D01*
X-113987Y-136784D01*
X-120755D01*
G01X-93430Y-130076D02*
X-94740Y-129200D01*
X-96268Y-128617D01*
X-98015D01*
X-99980Y-129492D01*
X-101508Y-130950D01*
X-102600Y-132701D01*
X-103473Y-135617D01*
X-103692Y-138242D01*
X-103255Y-140867D01*
X-102600Y-142617D01*
X-101290Y-144367D01*
X-99761Y-145534D01*
X-98233Y-146117D01*
X-96705D01*
X-95176Y-145534D01*
X-93866Y-144659D01*
X-92774Y-143493D01*
G01X-67600Y-128617D02*
Y-146117D01*
X-58866D01*
G01X-41366D02*
X-50100D01*
Y-128617D01*
X-41366D01*
G01X-44860Y-137075D02*
X-50100D01*
G01X-33036Y-146117D02*
Y-128617D01*
X-28670D01*
X-26923Y-129492D01*
X-25613Y-130659D01*
X-24521Y-132408D01*
X-23648Y-134451D01*
X-23430Y-137367D01*
X-23648Y-140284D01*
X-24521Y-142326D01*
X-25613Y-144076D01*
X-26923Y-145242D01*
X-28670Y-146117D01*
X-33036D01*
G01X10260Y-135909D02*
X8732Y-134742D01*
X7422Y-134451D01*
X5675Y-135034D01*
X4365Y-136200D01*
X3492Y-138242D01*
X3273Y-140284D01*
X3492Y-142326D01*
X4365Y-144076D01*
X5675Y-145534D01*
X7422Y-146117D01*
X8950Y-145534D01*
X10260Y-144367D01*
G01X28197Y-146117D02*
Y-134451D01*
G01Y-136492D02*
X27324Y-135326D01*
X26013Y-134742D01*
X24485Y-134451D01*
X22957Y-135034D01*
X21647Y-136200D01*
X20773Y-137950D01*
X20337Y-140284D01*
X20773Y-142617D01*
X21647Y-144367D01*
X22957Y-145534D01*
X24485Y-146117D01*
X26013Y-145825D01*
X27324Y-144951D01*
X28197Y-143784D01*
G01X38710Y-146117D02*
Y-134451D01*
G01Y-136784D02*
X39802Y-135617D01*
X40894Y-134742D01*
X42422Y-134451D01*
X43513Y-134742D01*
X44824Y-135617D01*
G01X63197Y-128617D02*
Y-146117D01*
G01Y-143493D02*
X62324Y-144951D01*
X61013Y-145825D01*
X59485Y-146117D01*
X57739Y-145534D01*
X56429Y-144076D01*
X55555Y-142326D01*
X55337Y-140284D01*
X55555Y-138242D01*
X56429Y-136492D01*
X57739Y-135034D01*
X59485Y-134451D01*
X61013Y-134742D01*
X62105Y-135326D01*
X63197Y-136492D01*
G01X-77660Y-101117D02*
Y-83617D01*
X-71983Y-98200D01*
X-66306Y-83617D01*
Y-101117D01*
G01X-54483D02*
X-55793Y-100825D01*
X-57103Y-99659D01*
X-57977Y-97617D01*
X-58413Y-95284D01*
X-57977Y-92950D01*
X-57103Y-90909D01*
X-55793Y-89742D01*
X-54483Y-89451D01*
X-53173Y-89742D01*
X-51863Y-90909D01*
X-50990Y-92950D01*
X-50771Y-95284D01*
X-50990Y-97617D01*
X-51863Y-99659D01*
X-53173Y-100825D01*
X-54483Y-101117D01*
G01X-33053Y-83617D02*
Y-101117D01*
G01Y-98493D02*
X-33926Y-99951D01*
X-35237Y-100825D01*
X-36765Y-101117D01*
X-38511Y-100534D01*
X-39821Y-99076D01*
X-40695Y-97326D01*
X-40913Y-95284D01*
X-40695Y-93242D01*
X-39821Y-91492D01*
X-38511Y-90034D01*
X-36765Y-89451D01*
X-35237Y-89742D01*
X-34145Y-90326D01*
X-33053Y-91492D01*
G01X-22758Y-93242D02*
X-15771D01*
X-16426Y-91200D01*
X-17518Y-90034D01*
X-19046Y-89451D01*
X-20575Y-89742D01*
X-21885Y-90617D01*
X-22758Y-92659D01*
X-23195Y-94409D01*
Y-96159D01*
X-22758Y-97909D01*
X-21666Y-99659D01*
X-20356Y-100825D01*
X-18828Y-101117D01*
X-17300Y-100534D01*
X-15771Y-98784D01*
G01X-1983Y-101117D02*
Y-83617D01*
G01X110317Y-146117D02*
Y-128617D01*
X107697Y-132117D01*
G01Y-146117D02*
X112937D01*
G01X123669Y-138826D02*
X125197Y-136784D01*
X126507Y-135617D01*
X128254Y-135034D01*
X129782Y-135617D01*
X130874Y-136784D01*
X131747Y-138534D01*
X131965Y-140575D01*
X131747Y-142326D01*
X130874Y-144076D01*
X129563Y-145534D01*
X128035Y-146117D01*
X126289Y-145534D01*
X124760Y-143784D01*
X123887Y-141159D01*
X123669Y-138242D01*
X124105Y-134451D01*
X124760Y-132408D01*
X125852Y-130367D01*
X127380Y-128909D01*
X128909Y-128617D01*
X130437Y-129200D01*
X131529Y-130659D01*
G01X140514Y-142617D02*
X141823Y-144659D01*
X143570Y-145825D01*
X145535Y-146117D01*
X147282Y-145825D01*
X149029Y-144367D01*
X150120Y-142617D01*
X150339Y-140867D01*
X149902Y-138826D01*
X148374Y-137367D01*
X146845Y-136784D01*
X144880D01*
G01X146845D02*
X148155Y-135909D01*
X149247Y-134451D01*
X149684Y-132701D01*
X149247Y-130950D01*
X148155Y-129492D01*
X146190Y-128617D01*
X144225Y-128909D01*
X142260Y-130076D01*
G01X158669Y-138826D02*
X160197Y-136784D01*
X161507Y-135617D01*
X163254Y-135034D01*
X164782Y-135617D01*
X165874Y-136784D01*
X166747Y-138534D01*
X166965Y-140575D01*
X166747Y-142326D01*
X165874Y-144076D01*
X164563Y-145534D01*
X163035Y-146117D01*
X161289Y-145534D01*
X159760Y-143784D01*
X158887Y-141159D01*
X158669Y-138242D01*
X159105Y-134451D01*
X159760Y-132408D01*
X160852Y-130367D01*
X162380Y-128909D01*
X163909Y-128617D01*
X165437Y-129200D01*
X166529Y-130659D01*
G01X180317Y-146117D02*
X181845Y-145825D01*
X183592Y-144951D01*
X184684Y-143493D01*
X185120Y-141450D01*
X184684Y-139409D01*
X183374Y-137659D01*
X181409Y-136784D01*
X179225D01*
X177915Y-136200D01*
X176823Y-134742D01*
X176387Y-132701D01*
X177042Y-130659D01*
X178570Y-129200D01*
X180317Y-128617D01*
X182063Y-129200D01*
X183592Y-130659D01*
X184247Y-132701D01*
X183810Y-134742D01*
X182719Y-136200D01*
X181409Y-136784D01*
X179225D01*
X177260Y-137659D01*
X175950Y-139409D01*
X175514Y-141450D01*
X175950Y-143493D01*
X177042Y-144951D01*
X178789Y-145825D01*
X180317Y-146117D01*
G01X97200Y-101117D02*
Y-83617D01*
X102440D01*
X104187Y-84492D01*
X105497Y-86534D01*
X105934Y-88867D01*
X105497Y-91200D01*
X104405Y-92950D01*
X102440Y-93826D01*
X97200D01*
G01X123870Y-85076D02*
X122560Y-84200D01*
X121032Y-83617D01*
X119285D01*
X117320Y-84492D01*
X115792Y-85950D01*
X114700Y-87701D01*
X113827Y-90617D01*
X113608Y-93242D01*
X114045Y-95867D01*
X114700Y-97617D01*
X116010Y-99367D01*
X117539Y-100534D01*
X119067Y-101117D01*
X120595D01*
X122124Y-100534D01*
X123434Y-99659D01*
X124526Y-98493D01*
G01X138313Y-91784D02*
X139187Y-90909D01*
X139842Y-89451D01*
X140279Y-87408D01*
X139842Y-85659D01*
X138969Y-84492D01*
X137440Y-83617D01*
X131545D01*
Y-101117D01*
X138750D01*
X140279Y-99951D01*
X141152Y-98200D01*
X141589Y-96159D01*
X141152Y-94117D01*
X139842Y-92367D01*
X138313Y-91784D01*
X131545D01*
G01X147517Y-106950D02*
X160617D01*
G01X166545Y-101117D02*
Y-83617D01*
X176589Y-101117D01*
Y-83617D01*
G01X189067Y-101117D02*
X187320Y-100825D01*
X185792Y-99659D01*
X184482Y-97909D01*
X183608Y-95867D01*
X183172Y-93534D01*
Y-91200D01*
X183608Y-88867D01*
X184482Y-86825D01*
X185792Y-85076D01*
X187320Y-83909D01*
X189067Y-83617D01*
X190813Y-83909D01*
X192342Y-85076D01*
X193652Y-86825D01*
X194526Y-88867D01*
X194962Y-91200D01*
Y-93534D01*
X194526Y-95867D01*
X193652Y-97909D01*
X192342Y-99659D01*
X190813Y-100825D01*
X189067Y-101117D01*
G01X258282Y-143784D02*
X260029Y-145242D01*
X261994Y-146117D01*
X263740D01*
X265487Y-145242D01*
X266797Y-143784D01*
X267452Y-141742D01*
X267015Y-139701D01*
X265924Y-137950D01*
X263959Y-136784D01*
X261339Y-136200D01*
X259810Y-135034D01*
X259155Y-132992D01*
X259592Y-130950D01*
X260684Y-129492D01*
X262212Y-128617D01*
X263740D01*
X265269Y-129200D01*
X266579Y-130659D01*
G01X282113Y-136784D02*
X282987Y-135909D01*
X283642Y-134451D01*
X284079Y-132408D01*
X283642Y-130659D01*
X282769Y-129492D01*
X281240Y-128617D01*
X275345D01*
Y-146117D01*
X282550D01*
X284079Y-144951D01*
X284952Y-143200D01*
X285389Y-141159D01*
X284952Y-139117D01*
X283642Y-137367D01*
X282113Y-136784D01*
X275345D01*
G01X239908Y-83617D02*
X245367Y-101117D01*
X250826Y-83617D01*
G01X267234Y-101117D02*
X258500D01*
Y-83617D01*
X267234D01*
G01X263740Y-92075D02*
X258500D01*
G01X276000Y-101117D02*
Y-83617D01*
X281459D01*
X283205Y-84492D01*
X284297Y-85659D01*
X284734Y-87992D01*
X284297Y-90326D01*
X282987Y-91784D01*
X281459Y-92659D01*
X276000D01*
G01X281459D02*
X284734Y-101117D01*
G01X297867Y-101700D02*
X297430Y-101409D01*
Y-100825D01*
X297867Y-100534D01*
X298304Y-100825D01*
Y-101409D01*
X297867Y-101700D01*
G01X446071Y-136784D02*
X445197Y-135909D01*
X444542Y-134451D01*
X444105Y-132408D01*
X444542Y-130659D01*
X445415Y-129492D01*
X446944Y-128617D01*
X452839D01*
Y-146117D01*
X445634D01*
X444105Y-144951D01*
X443232Y-143200D01*
X442795Y-141159D01*
X443232Y-139117D01*
X444542Y-137367D01*
X446071Y-136784D01*
X452839D01*
G01X435994Y-146117D02*
Y-128617D01*
X430317Y-143200D01*
X424640Y-128617D01*
Y-146117D01*
G01X418276D02*
X412817Y-128617D01*
X407358Y-146117D01*
G01X409324Y-139992D02*
X416311D01*
G01X399902Y-143784D02*
X398155Y-145242D01*
X396190Y-146117D01*
X394444D01*
X392697Y-145242D01*
X391387Y-143784D01*
X390732Y-141742D01*
X391169Y-139701D01*
X392260Y-137950D01*
X394225Y-136784D01*
X396845Y-136200D01*
X398374Y-135034D01*
X399029Y-132992D01*
X398592Y-130950D01*
X397500Y-129492D01*
X395972Y-128617D01*
X394444D01*
X392915Y-129200D01*
X391605Y-130659D01*
G01X382620Y-146117D02*
Y-128617D01*
G01X374324D02*
X382620Y-139409D01*
G01X373014Y-146117D02*
X378909Y-134451D01*
G01X373450Y-83617D02*
Y-101117D01*
X382184D01*
G01X399247D02*
Y-89451D01*
G01Y-91492D02*
X398374Y-90326D01*
X397063Y-89742D01*
X395535Y-89451D01*
X394007Y-90034D01*
X392697Y-91200D01*
X391823Y-92950D01*
X391387Y-95284D01*
X391823Y-97617D01*
X392697Y-99367D01*
X394007Y-100534D01*
X395535Y-101117D01*
X397063Y-100825D01*
X398374Y-99951D01*
X399247Y-98784D01*
G01X408232Y-106367D02*
X409542Y-106950D01*
X411289Y-106367D01*
X412380Y-105201D01*
X413254Y-103742D01*
X414563Y-99076D01*
X417402Y-89451D01*
G01X410415D02*
X414563Y-99076D01*
G01X427042Y-93242D02*
X434029D01*
X433374Y-91200D01*
X432282Y-90034D01*
X430754Y-89451D01*
X429225Y-89742D01*
X427915Y-90617D01*
X427042Y-92659D01*
X426605Y-94409D01*
Y-96159D01*
X427042Y-97909D01*
X428134Y-99659D01*
X429444Y-100825D01*
X430972Y-101117D01*
X432500Y-100534D01*
X434029Y-98784D01*
G01X444760Y-101117D02*
Y-89451D01*
G01Y-91784D02*
X445852Y-90617D01*
X446944Y-89742D01*
X448472Y-89451D01*
X449563Y-89742D01*
X450874Y-90617D01*
G01X515564Y-101117D02*
Y-83617D01*
X519930D01*
X521677Y-84492D01*
X522987Y-85659D01*
X524079Y-87408D01*
X524952Y-89451D01*
X525170Y-92367D01*
X524952Y-95284D01*
X524079Y-97326D01*
X522987Y-99076D01*
X521677Y-100242D01*
X519930Y-101117D01*
X515564D01*
G01X534592Y-93242D02*
X541579D01*
X540924Y-91200D01*
X539832Y-90034D01*
X538304Y-89451D01*
X536775Y-89742D01*
X535465Y-90617D01*
X534592Y-92659D01*
X534155Y-94409D01*
Y-96159D01*
X534592Y-97909D01*
X535684Y-99659D01*
X536994Y-100825D01*
X538522Y-101117D01*
X540050Y-100534D01*
X541579Y-98784D01*
G01X552092Y-99076D02*
X553184Y-100242D01*
X554712Y-101117D01*
X556022D01*
X557332Y-100534D01*
X558205Y-99659D01*
X558642Y-98493D01*
X558424Y-96742D01*
X557550Y-95867D01*
X553620Y-94117D01*
X552747Y-92075D01*
X553184Y-90617D01*
X554057Y-89742D01*
X555367Y-89451D01*
X556677Y-89742D01*
X557987Y-90617D01*
G01X572867Y-89451D02*
Y-101117D01*
G01Y-84784D02*
X572430Y-84492D01*
Y-83909D01*
X572867Y-83617D01*
X573304Y-83909D01*
Y-84492D01*
X572867Y-84784D01*
G01X587310Y-105492D02*
X588839Y-106659D01*
X590585Y-106950D01*
X592113Y-106659D01*
X593424Y-105201D01*
X594297Y-103159D01*
Y-89451D01*
G01Y-91784D02*
X593424Y-90617D01*
X592113Y-89742D01*
X590585Y-89451D01*
X588839Y-90034D01*
X587747Y-91200D01*
X586873Y-93242D01*
X586437Y-95284D01*
X586655Y-97034D01*
X587529Y-99076D01*
X588839Y-100534D01*
X590585Y-101117D01*
X591895Y-100825D01*
X593424Y-99659D01*
X594297Y-98493D01*
G01X604155Y-101117D02*
Y-89451D01*
G01Y-92367D02*
X605029Y-90909D01*
X606339Y-89742D01*
X608085Y-89451D01*
X609613Y-89742D01*
X610924Y-90909D01*
X611579Y-92950D01*
Y-101117D01*
G01X622092Y-93242D02*
X629079D01*
X628424Y-91200D01*
X627332Y-90034D01*
X625804Y-89451D01*
X624275Y-89742D01*
X622965Y-90617D01*
X622092Y-92659D01*
X621655Y-94409D01*
Y-96159D01*
X622092Y-97909D01*
X623184Y-99659D01*
X624494Y-100825D01*
X626022Y-101117D01*
X627550Y-100534D01*
X629079Y-98784D01*
G01X639810Y-101117D02*
Y-89451D01*
G01Y-91784D02*
X640902Y-90617D01*
X641994Y-89742D01*
X643522Y-89451D01*
X644613Y-89742D01*
X645924Y-90617D01*
G01X559969Y-128617D02*
X568265D01*
X559969Y-146117D01*
X568265D01*
G01X581617D02*
X579870Y-145825D01*
X578342Y-144659D01*
X577032Y-142909D01*
X576158Y-140867D01*
X575722Y-138534D01*
Y-136200D01*
X576158Y-133867D01*
X577032Y-131825D01*
X578342Y-130076D01*
X579870Y-128909D01*
X581617Y-128617D01*
X583363Y-128909D01*
X584892Y-130076D01*
X586202Y-131825D01*
X587076Y-133867D01*
X587512Y-136200D01*
Y-138534D01*
X587076Y-140867D01*
X586202Y-142909D01*
X584892Y-144659D01*
X583363Y-145825D01*
X581617Y-146117D01*
G01X603484D02*
X594750D01*
Y-128617D01*
X603484D01*
G01X599990Y-137075D02*
X594750D01*
G01X686567Y-128617D02*
X684820Y-129200D01*
X683510Y-130659D01*
X682637Y-132408D01*
X681982Y-134742D01*
X681764Y-137367D01*
X681982Y-139992D01*
X682637Y-142326D01*
X683510Y-144076D01*
X684820Y-145534D01*
X686567Y-146117D01*
X688313Y-145534D01*
X689624Y-144076D01*
X690497Y-142326D01*
X691152Y-139992D01*
X691370Y-137367D01*
X691152Y-134742D01*
X690497Y-132408D01*
X689624Y-130659D01*
X688313Y-129200D01*
X686567Y-128617D01*
G01X699919Y-131534D02*
X701229Y-129784D01*
X702757Y-128909D01*
X704504Y-128617D01*
X706687Y-129200D01*
X708215Y-130659D01*
X708652Y-132408D01*
X708434Y-134159D01*
X707560Y-135617D01*
X703194Y-138534D01*
X701229Y-140575D01*
X699919Y-143493D01*
X699482Y-146117D01*
X708652D01*
G01X717637Y-146700D02*
X725497Y-128617D01*
G01X739067D02*
X737320Y-129200D01*
X736010Y-130659D01*
X735137Y-132408D01*
X734482Y-134742D01*
X734264Y-137367D01*
X734482Y-139992D01*
X735137Y-142326D01*
X736010Y-144076D01*
X737320Y-145534D01*
X739067Y-146117D01*
X740813Y-145534D01*
X742124Y-144076D01*
X742997Y-142326D01*
X743652Y-139992D01*
X743870Y-137367D01*
X743652Y-134742D01*
X742997Y-132408D01*
X742124Y-130659D01*
X740813Y-129200D01*
X739067Y-128617D01*
G01X756130Y-146117D02*
X756567Y-142326D01*
X757222Y-139117D01*
X758095Y-136200D01*
X759187Y-132992D01*
X760934Y-128617D01*
X752200D01*
G01X770137Y-146700D02*
X777997Y-128617D01*
G01X787419Y-131534D02*
X788729Y-129784D01*
X790257Y-128909D01*
X792004Y-128617D01*
X794187Y-129200D01*
X795715Y-130659D01*
X796152Y-132408D01*
X795934Y-134159D01*
X795060Y-135617D01*
X790694Y-138534D01*
X788729Y-140575D01*
X787419Y-143493D01*
X786982Y-146117D01*
X796152D01*
G01X809067Y-128617D02*
X807320Y-129200D01*
X806010Y-130659D01*
X805137Y-132408D01*
X804482Y-134742D01*
X804264Y-137367D01*
X804482Y-139992D01*
X805137Y-142326D01*
X806010Y-144076D01*
X807320Y-145534D01*
X809067Y-146117D01*
X810813Y-145534D01*
X812124Y-144076D01*
X812997Y-142326D01*
X813652Y-139992D01*
X813870Y-137367D01*
X813652Y-134742D01*
X812997Y-132408D01*
X812124Y-130659D01*
X810813Y-129200D01*
X809067Y-128617D01*
G01X826567Y-146117D02*
Y-128617D01*
X823947Y-132117D01*
G01Y-146117D02*
X829187D01*
G01X843630D02*
X844067Y-142326D01*
X844722Y-139117D01*
X845595Y-136200D01*
X846687Y-132992D01*
X848434Y-128617D01*
X839700D01*
G01X734264Y-101117D02*
Y-83617D01*
X738630D01*
X740377Y-84492D01*
X741687Y-85659D01*
X742779Y-87408D01*
X743652Y-89451D01*
X743870Y-92367D01*
X743652Y-95284D01*
X742779Y-97326D01*
X741687Y-99076D01*
X740377Y-100242D01*
X738630Y-101117D01*
X734264D01*
G01X760497D02*
Y-89451D01*
G01Y-91492D02*
X759624Y-90326D01*
X758313Y-89742D01*
X756785Y-89451D01*
X755257Y-90034D01*
X753947Y-91200D01*
X753073Y-92950D01*
X752637Y-95284D01*
X753073Y-97617D01*
X753947Y-99367D01*
X755257Y-100534D01*
X756785Y-101117D01*
X758313Y-100825D01*
X759624Y-99951D01*
X760497Y-98784D01*
G01X774067Y-83617D02*
Y-101117D01*
G01X771010Y-89451D02*
X777124D01*
G01X788292Y-93242D02*
X795279D01*
X794624Y-91200D01*
X793532Y-90034D01*
X792004Y-89451D01*
X790475Y-89742D01*
X789165Y-90617D01*
X788292Y-92659D01*
X787855Y-94409D01*
Y-96159D01*
X788292Y-97909D01*
X789384Y-99659D01*
X790694Y-100825D01*
X792222Y-101117D01*
X793750Y-100534D01*
X795279Y-98784D01*
G54D19*
X74500Y27800D03*
X70000Y48300D03*
G54D28*
X113000Y19300D03*
X63000Y39000D03*
X74000Y56200D03*
X73500Y42000D03*
X156000Y53500D03*
G54D29*
X103642Y43898D03*
X127264D03*
M02*
